FILE_TYPE = CONNECTIVITY;
{Allegro Design Entry HDL 17.4-2019 S026 (4007227) 1/17/2022}
"PAGE_NUMBER" = 332;
0"NC";
1"GND\g";
2"P3V3_AUX\g";
3"GND\g";
4"P3V3_AUX\g";
5"P3V3_AUX\g";
6"P3V3_AUX\g";
7"P3V3_AUX\g";
8"GND\g";
9"P3V3_AUX\g";
10"GND\g";
11"GND\g";
12"GND\g";
13"P3V3_AUX\g";
14"GND\g";
15"GND\g";
16"GND\g";
17"P3V3_AUX\g";
18"P3V3_AUX\g";
19"GND\g";
20"P3V3_AUX\g";
21"GND\g";
22"P3V3_AUX\g";
23"GND\g";
24"P3V3_AUX\g";
25"GND\g";
26"P3V3_AUX\g";
27"P3V3_AUX\g";
28"GND\g";
29"P3V3_AUX\g";
30"GND\g";
31"GND\g";
32"GND\g";
33"GND\g";
34"P3V3_AUX\g";
35"GND\g";
36"P3V3_AUX\g";
37"GND\g";
38"GND\g";
39"GND\g";
40"P3V3_AUX\g";
41"GND\g";
42"GND\g";
43"GND\g";
44"P3V3_AUX\g";
45"GND\g";
46"GND\g";
47"GND\g";
48"P3V3_AUX\g";
49"GND\g";
50"P3V3_AUX\g";
51"GND\g";
52"P3V3_AUX\g";
53"P3V3_AUX\g";
54"GND\g";
55"P3V3_AUX\g";
56"GND\g";
57"SWB_HSC_PWRGD_ISO";
58"SWB_HSC_PWRGD";
59"PRSNT_CABLE_GPU_A1_ISO_N";
60"PRSNT_CABLE_GPU_B3_ISO_N";
61"GPU_3V3IO_RSVD1_FFU_ISO";
62"PRSNT_CABLE_GPU_A1";
63"SWB_HSC_PWRGD_N";
64"PRSNT_CABLE_GPU_B3";
65"GPU_3V3IO_RSVD0_FFU_N";
66"GPU_3V3IO_RSVD5_FFU_N";
67"PRSNT_CABLE_GPU_A2";
68"GPU_3V3IO_RSVD3_FFU_N";
69"GPU_3V3IO_RSVD1_FFU_N";
70"PRSNT_CABLE_GPU_A1_N";
71"PRSNT_CABLE_GPU_B3_N";
72"GPU_3V3IO_RSVD1_FFU";
73"GPU_3V3IO_RSVD0_FFU";
74"GPU_3V3IO_RSVD0_FFU_ISO";
75"GPU_3V3IO_RSVD5_FFU";
76"PRSNT_CABLE_GPU_A2_N";
77"GPU_3V3IO_RSVD3_FFU";
78"GPU_3V3IO_RSVD5_FFU_ISO";
79"PRSNT_CABLE_GPU_A2_ISO_N";
80"GPU_3V3IO_RSVD3_FFU_ISO";
%"UNIVERSAL_GND"
"1","(-2050,-1475)","0","pure_quanta_power","I1";
;
CDS_LIB"pure_quanta_power"
HDL_POWER"GND";
"A"1;
%"MOSFET_NCH_DUAL"
"2","(200,-650)","0","pure_quanta","I10";
;
LOCATION"Q134"
$SEC"2"
CDS_SEC"2"
MATERIAL"IC"
VALUE"PJT138K"
PART_TYPE"SMLF"
CDS_LMAN_SYM_OUTLINE"-150,150,150,-150"
NEEDS_NO_SIZE"TRUE"
CDS_LIB"pure_quanta"
PART_NUMBER"BAM138K0003";
"S2"
$PN"4"32;
"G2"
$PN"5"62;
"D2"
$PN"3"59;
%"UNIVERSAL_POWER"
"1","(3675,3175)","0","pure_quanta_power","I100";
;
HDL_POWER"P3V3_AUX"
CDS_LIB"pure_quanta_power";
"A"2;
%"UNIVERSAL_GND"
"1","(3650,3350)","0","pure_quanta_power","I101";
;
CDS_LIB"pure_quanta_power"
HDL_POWER"GND";
"A"3;
%"MOSFET_NCH_DUAL"
"1","(3600,3725)","0","pure_quanta","I102";
;
LOCATION"Q130"
$SEC"1"
CDS_SEC"1"
VALUE"PJT138K"
PART_TYPE"SMLF"
MATERIAL"IC"
CDS_LIB"pure_quanta"
NEEDS_NO_SIZE"TRUE"
CDS_LMAN_SYM_OUTLINE"-150,150,150,-150"
PART_NUMBER"BAM138K0003";
"D1"
$PN"6"68;
"G1"
$PN"2"77;
"S1"
$PN"1"3;
%"Q_RES"
"1","(4000,3325)","0","pure_quanta","I103";
;
LOCATION"R4578"
$SEC"1"
CDS_SEC"1"
MATERIAL"EMPTY"
VALUE"0"
TOLERANCE"5%"
PACK_TYPE"0402LF"
WATTAGE"1/16W"
CDS_LIB"pure_quanta"
PART_NUMBER"CS00002JB13";
"B"
$PN"2"79;
"A"
$PN"1"76;
%"Q_RES"
"2","(175,4150)","0","pure_quanta","I104";
;
LOCATION"R4128"
$SEC"1"
CDS_SEC"1"
VALUE"100K"
PACK_TYPE"0402LF"
MATERIAL"CHIP"
WATTAGE"1/16W"
TOLERANCE"1%"
CDS_LIB"pure_quanta"
PART_NUMBER"CS41002FB09";
"A"
$PN"1"4;
"B"
$PN"2"74;
%"UNIVERSAL_POWER"
"1","(175,4375)","0","pure_quanta_power","I105";
;
HDL_POWER"P3V3_AUX"
CDS_LIB"pure_quanta_power";
"A"4;
%"UNIVERSAL_POWER"
"1","(2475,4200)","0","pure_quanta_power","I106";
;
HDL_POWER"P3V3_AUX"
CDS_LIB"pure_quanta_power";
"A"5;
%"Q_RES"
"2","(3650,4325)","0","pure_quanta","I107";
;
LOCATION"R4137"
$SEC"1"
CDS_SEC"1"
TOLERANCE"5%"
VALUE"4.7K"
WATTAGE"1/16W"
PACK_TYPE"0402LF"
MATERIAL"CHIP"
CDS_LIB"pure_quanta"
PART_NUMBER"CS24702JB10";
"A"
$PN"1"6;
"B"
$PN"2"68;
%"UNIVERSAL_POWER"
"1","(3650,4550)","0","pure_quanta_power","I108";
;
HDL_POWER"P3V3_AUX"
CDS_LIB"pure_quanta_power";
"A"6;
%"Q_RES"
"1","(3950,4700)","0","pure_quanta","I109";
;
LOCATION"R4577"
$SEC"1"
CDS_SEC"1"
PACK_TYPE"0402LF"
WATTAGE"1/16W"
MATERIAL"EMPTY"
VALUE"0"
TOLERANCE"5%"
CDS_LIB"pure_quanta"
PART_NUMBER"CS00002JB13";
"B"
$PN"2"80;
"A"
$PN"1"77;
%"Q_RES"
"2","(4800,150)","0","pure_quanta","I110";
;
LOCATION"R4561"
$SEC"1"
CDS_SEC"1"
TOLERANCE"1%"
VALUE"100K"
WATTAGE"1/16W"
MATERIAL"CHIP"
PACK_TYPE"0402LF"
CDS_LIB"pure_quanta"
PART_NUMBER"CS41002FB09";
"A"
$PN"1"7;
"B"
$PN"2"57;
%"UNIVERSAL_POWER"
"1","(4800,375)","0","pure_quanta_power","I111";
;
HDL_POWER"P3V3_AUX"
CDS_LIB"pure_quanta_power";
"A"7;
%"UNIVERSAL_GND"
"1","(4800,825)","0","pure_quanta_power","I112";
;
CDS_LIB"pure_quanta_power"
HDL_POWER"GND";
"A"8;
%"MOSFET_NCH_DUAL"
"2","(4750,1200)","0","pure_quanta","I113";
;
LOCATION"Q129"
$SEC"2"
CDS_SEC"2"
PART_TYPE"SMLF"
VALUE"PJT138K"
MATERIAL"IC"
CDS_LMAN_SYM_OUTLINE"-150,150,150,-150"
NEEDS_NO_SIZE"TRUE"
CDS_LIB"pure_quanta"
PART_NUMBER"BAM138K0003";
"S2"
$PN"4"8;
"G2"
$PN"5"66;
"D2"
$PN"3"78;
%"Q_RES"
"2","(4800,1625)","0","pure_quanta","I114";
;
LOCATION"R4141"
$SEC"1"
CDS_SEC"1"
TOLERANCE"1%"
VALUE"100K"
MATERIAL"CHIP"
WATTAGE"1/16W"
PACK_TYPE"0402LF"
CDS_LIB"pure_quanta"
PART_NUMBER"CS41002FB09";
"A"
$PN"1"9;
"B"
$PN"2"78;
%"UNIVERSAL_POWER"
"1","(4800,1850)","0","pure_quanta_power","I115";
;
HDL_POWER"P3V3_AUX"
CDS_LIB"pure_quanta_power";
"A"9;
%"UNIVERSAL_GND"
"1","(5575,950)","0","pure_quanta_power","I116";
;
CDS_LIB"pure_quanta_power"
HDL_POWER"GND";
"A"10;
%"Q_CAP"
"1","(5575,1150)","0","pure_quanta","I118";
;
LOCATION"C17"
$SEC"1"
CDS_SEC"1"
VOLTAGE"25V"
TOLERANCE"10%"
PACK_TYPE"0402"
MATERIAL"X7R"
VALUE"0.1UF"
CDS_LIB"pure_quanta"
PART_NUMBER"CH4104K1B00";
"B"
$PN"2"10;
"A"
$PN"1"78;
%"UNIVERSAL_GND"
"1","(-2125,75)","0","pure_quanta_power","I12";
;
CDS_LIB"pure_quanta_power"
HDL_POWER"GND";
"A"11;
%"MOSFET_NCH_DUAL"
"2","(4775,2650)","0","pure_quanta","I120";
;
LOCATION"Q133"
$SEC"2"
CDS_SEC"2"
VALUE"PJT138K"
PART_TYPE"SMLF"
MATERIAL"IC"
CDS_LMAN_SYM_OUTLINE"-150,150,150,-150"
NEEDS_NO_SIZE"TRUE"
CDS_LIB"pure_quanta"
PART_NUMBER"BAM138K0003";
"S2"
$PN"4"12;
"G2"
$PN"5"67;
"D2"
$PN"3"79;
%"UNIVERSAL_GND"
"1","(4825,2275)","0","pure_quanta_power","I121";
;
CDS_LIB"pure_quanta_power"
HDL_POWER"GND";
"A"12;
%"Q_RES"
"2","(4825,3075)","0","pure_quanta","I122";
;
LOCATION"R4142"
$SEC"1"
CDS_SEC"1"
TOLERANCE"1%"
VALUE"100K"
WATTAGE"1/16W"
MATERIAL"CHIP"
PACK_TYPE"0402LF"
CDS_LIB"pure_quanta"
PART_NUMBER"CS41002FB09";
"A"
$PN"1"13;
"B"
$PN"2"79;
%"MOSFET_NCH_DUAL"
"2","(4750,4025)","0","pure_quanta","I123";
;
LOCATION"Q130"
$SEC"2"
CDS_SEC"2"
MATERIAL"IC"
VALUE"PJT138K"
PART_TYPE"SMLF"
CDS_LMAN_SYM_OUTLINE"-150,150,150,-150"
NEEDS_NO_SIZE"TRUE"
CDS_LIB"pure_quanta"
PART_NUMBER"BAM138K0003";
"S2"
$PN"4"14;
"G2"
$PN"5"68;
"D2"
$PN"3"80;
%"UNIVERSAL_POWER"
"1","(4825,3300)","0","pure_quanta_power","I124";
;
HDL_POWER"P3V3_AUX"
CDS_LIB"pure_quanta_power";
"A"13;
%"UNIVERSAL_GND"
"1","(4800,3650)","0","pure_quanta_power","I125";
;
CDS_LIB"pure_quanta_power"
HDL_POWER"GND";
"A"14;
%"UNIVERSAL_GND"
"1","(5600,2400)","0","pure_quanta_power","I126";
;
CDS_LIB"pure_quanta_power"
HDL_POWER"GND";
"A"15;
%"Q_CAP"
"1","(5600,2600)","0","pure_quanta","I127";
;
LOCATION"C19"
$SEC"1"
CDS_SEC"1"
PACK_TYPE"0402"
TOLERANCE"10%"
VOLTAGE"25V"
VALUE"0.1UF"
MATERIAL"X7R"
CDS_LIB"pure_quanta"
PART_NUMBER"CH4104K1B00";
"B"
$PN"2"15;
"A"
$PN"1"79;
%"UNIVERSAL_GND"
"1","(5575,3775)","0","pure_quanta_power","I129";
;
CDS_LIB"pure_quanta_power"
HDL_POWER"GND";
"A"16;
%"Q_RES"
"2","(-2125,350)","0","pure_quanta","I13";
;
LOCATION"R4122"
$SEC"1"
CDS_SEC"1"
PACK_TYPE"0402LF"
WATTAGE"1/16W"
TOLERANCE"1%"
VALUE"100K"
MATERIAL"EMPTY"
CDS_LIB"pure_quanta"
PART_NUMBER"CS41002FB09";
"A"
$PN"1"71;
"B"
$PN"2"11;
%"Q_CAP"
"1","(5575,3975)","0","pure_quanta","I130";
;
LOCATION"C16"
$SEC"1"
CDS_SEC"1"
VOLTAGE"25V"
VALUE"0.1UF"
TOLERANCE"10%"
PACK_TYPE"0402"
MATERIAL"X7R"
CDS_LIB"pure_quanta"
PART_NUMBER"CH4104K1B00";
"B"
$PN"2"16;
"A"
$PN"1"80;
%"Q_RES"
"2","(4800,4450)","0","pure_quanta","I131";
;
LOCATION"R4140"
$SEC"1"
CDS_SEC"1"
VALUE"100K"
TOLERANCE"1%"
WATTAGE"1/16W"
PACK_TYPE"0402LF"
MATERIAL"CHIP"
CDS_LIB"pure_quanta"
PART_NUMBER"CS41002FB09";
"A"
$PN"1"17;
"B"
$PN"2"80;
%"UNIVERSAL_POWER"
"1","(4800,4675)","0","pure_quanta_power","I132";
;
HDL_POWER"P3V3_AUX"
CDS_LIB"pure_quanta_power";
"A"17;
%"MOSFET_NCH_DUAL"
"2","(4750,-275)","0","pure_quanta","I134";
;
LOCATION"Q146"
$SEC"2"
CDS_SEC"2"
PART_TYPE"SMLF"
MATERIAL"IC"
VALUE"PJT138K"
CDS_LMAN_SYM_OUTLINE"-150,150,150,-150"
NEEDS_NO_SIZE"TRUE"
CDS_LIB"pure_quanta"
PART_NUMBER"BAM138K0003";
"S2"
$PN"4"38;
"G2"
$PN"5"63;
"D2"
$PN"3"57;
%"Q_RES"
"2","(-2100,1800)","0","pure_quanta","I135";
;
LOCATION"R4124"
$SEC"1"
CDS_SEC"1"
MATERIAL"EMPTY"
TOLERANCE"1%"
VALUE"100K"
PACK_TYPE"0402LF"
WATTAGE"1/16W"
CDS_LIB"pure_quanta"
PART_NUMBER"CS41002FB09";
"A"
$PN"1"72;
"B"
$PN"2"19;
%"Q_RES"
"2","(-2150,825)","0","pure_quanta","I14";
;
LOCATION"R4121"
$SEC"1"
CDS_SEC"1"
TOLERANCE"1%"
PACK_TYPE"0402LF"
VALUE"10K"
MATERIAL"CHIP"
WATTAGE"1/16W"
CDS_LIB"pure_quanta"
PART_NUMBER"CS31002FB08";
"A"
$PN"1"18;
"B"
$PN"2"71;
%"UNIVERSAL_POWER"
"1","(-2150,1075)","0","pure_quanta_power","I16";
;
HDL_POWER"P3V3_AUX"
CDS_LIB"pure_quanta_power";
"A"18;
%"UNIVERSAL_GND"
"1","(-2100,1525)","0","pure_quanta_power","I17";
;
CDS_LIB"pure_quanta_power"
HDL_POWER"GND";
"A"19;
%"Q_RES"
"2","(-2125,2275)","0","pure_quanta","I18";
;
LOCATION"R4123"
$SEC"1"
CDS_SEC"1"
MATERIAL"EMPTY"
PACK_TYPE"0402LF"
WATTAGE"1/16W"
TOLERANCE"1%"
VALUE"54.9K"
CDS_LIB"pure_quanta"
PART_NUMBER"CS35492FB03";
"A"
$PN"1"20;
"B"
$PN"2"72;
%"UNIVERSAL_POWER"
"1","(-2125,2525)","0","pure_quanta_power","I19";
;
HDL_POWER"P3V3_AUX"
CDS_LIB"pure_quanta_power";
"A"20;
%"Q_RES"
"2","(-2050,-1200)","0","pure_quanta","I2";
;
LOCATION"R4154"
$SEC"1"
CDS_SEC"1"
PACK_TYPE"0402LF"
TOLERANCE"1%"
VALUE"100K"
MATERIAL"EMPTY"
WATTAGE"1/16W"
CDS_LIB"pure_quanta"
PART_NUMBER"CS41002FB09";
"A"
$PN"1"70;
"B"
$PN"2"1;
%"UNIVERSAL_GND"
"1","(-2125,2900)","0","pure_quanta_power","I20";
;
CDS_LIB"pure_quanta_power"
HDL_POWER"GND";
"A"21;
%"Q_RES"
"2","(-2125,3175)","0","pure_quanta","I22";
;
LOCATION"R4120"
$SEC"1"
CDS_SEC"1"
MATERIAL"EMPTY"
WATTAGE"1/16W"
TOLERANCE"1%"
VALUE"100K"
PACK_TYPE"0402LF"
CDS_LIB"pure_quanta"
PART_NUMBER"CS41002FB09";
"A"
$PN"1"73;
"B"
$PN"2"21;
%"Q_RES"
"2","(-2150,3650)","0","pure_quanta","I23";
;
LOCATION"R4119"
$SEC"1"
CDS_SEC"1"
MATERIAL"EMPTY"
WATTAGE"1/16W"
VALUE"54.9K"
TOLERANCE"1%"
PACK_TYPE"0402LF"
CDS_LIB"pure_quanta"
PART_NUMBER"CS35492FB03";
"A"
$PN"1"22;
"B"
$PN"2"73;
%"UNIVERSAL_POWER"
"1","(-2150,3900)","0","pure_quanta_power","I24";
;
HDL_POWER"P3V3_AUX"
CDS_LIB"pure_quanta_power";
"A"22;
%"MOSFET_NCH_DUAL"
"1","(-1025,600)","0","pure_quanta","I25";
;
LOCATION"Q132"
$SEC"1"
CDS_SEC"1"
MATERIAL"IC"
PART_TYPE"SMLF"
VALUE"PJT138K"
CDS_LIB"pure_quanta"
NEEDS_NO_SIZE"TRUE"
CDS_LMAN_SYM_OUTLINE"-150,150,150,-150"
PART_NUMBER"BAM138K0003";
"D1"
$PN"6"64;
"G1"
$PN"2"71;
"S1"
$PN"1"23;
%"UNIVERSAL_GND"
"1","(-975,225)","0","pure_quanta_power","I26";
;
CDS_LIB"pure_quanta_power"
HDL_POWER"GND";
"A"23;
%"Q_RES"
"2","(-975,1200)","0","pure_quanta","I27";
;
LOCATION"R4126"
$SEC"1"
CDS_SEC"1"
WATTAGE"1/16W"
TOLERANCE"5%"
MATERIAL"CHIP"
VALUE"4.7K"
PACK_TYPE"0402LF"
CDS_LIB"pure_quanta"
PART_NUMBER"CS24702JB10";
"A"
$PN"1"24;
"B"
$PN"2"64;
%"UNIVERSAL_POWER"
"1","(-975,1425)","0","pure_quanta_power","I28";
;
HDL_POWER"P3V3_AUX"
CDS_LIB"pure_quanta_power";
"A"24;
%"UNIVERSAL_GND"
"1","(-950,1675)","0","pure_quanta_power","I29";
;
CDS_LIB"pure_quanta_power"
HDL_POWER"GND";
"A"25;
%"MOSFET_NCH_DUAL"
"1","(-1000,2050)","0","pure_quanta","I30";
;
LOCATION"Q131"
$SEC"1"
CDS_SEC"1"
VALUE"PJT138K"
PART_TYPE"SMLF"
MATERIAL"IC"
CDS_LMAN_SYM_OUTLINE"-150,150,150,-150"
NEEDS_NO_SIZE"TRUE"
CDS_LIB"pure_quanta"
PART_NUMBER"BAM138K0003";
"D1"
$PN"6"69;
"G1"
$PN"2"72;
"S1"
$PN"1"25;
%"Q_RES"
"1","(-625,25)","0","pure_quanta","I31";
;
LOCATION"R4574"
$SEC"1"
CDS_SEC"1"
VALUE"0"
TOLERANCE"5%"
MATERIAL"EMPTY"
WATTAGE"1/16W"
PACK_TYPE"0402LF"
CDS_LIB"pure_quanta"
PART_NUMBER"CS00002JB13";
"B"
$PN"2"59;
"A"
$PN"1"70;
%"MOSFET_NCH_DUAL"
"2","(125,900)","0","pure_quanta","I32";
;
LOCATION"Q132"
$SEC"2"
CDS_SEC"2"
PART_TYPE"SMLF"
MATERIAL"IC"
VALUE"PJT138K"
CDS_LIB"pure_quanta"
NEEDS_NO_SIZE"TRUE"
CDS_LMAN_SYM_OUTLINE"-150,150,150,-150"
PART_NUMBER"BAM138K0003";
"S2"
$PN"4"31;
"G2"
$PN"5"64;
"D2"
$PN"3"60;
%"Q_RES"
"1","(-700,1575)","0","pure_quanta","I33";
;
LOCATION"R4573"
$SEC"1"
CDS_SEC"1"
TOLERANCE"5%"
VALUE"0"
MATERIAL"EMPTY"
WATTAGE"1/16W"
PACK_TYPE"0402LF"
CDS_LIB"pure_quanta"
PART_NUMBER"CS00002JB13";
"B"
$PN"2"60;
"A"
$PN"1"71;
%"UNIVERSAL_POWER"
"1","(0,1475)","0","pure_quanta_power","I34";
;
HDL_POWER"P3V3_AUX"
CDS_LIB"pure_quanta_power";
"A"26;
%"Q_RES"
"2","(-950,2650)","0","pure_quanta","I35";
;
LOCATION"R4127"
$SEC"1"
CDS_SEC"1"
TOLERANCE"5%"
PACK_TYPE"0402LF"
WATTAGE"1/16W"
MATERIAL"CHIP"
VALUE"4.7K"
CDS_LIB"pure_quanta"
PART_NUMBER"CS24702JB10";
"A"
$PN"1"27;
"B"
$PN"2"69;
%"UNIVERSAL_POWER"
"1","(-950,2875)","0","pure_quanta_power","I36";
;
HDL_POWER"P3V3_AUX"
CDS_LIB"pure_quanta_power";
"A"27;
%"MOSFET_NCH_DUAL"
"1","(-1025,3425)","0","pure_quanta","I37";
;
LOCATION"Q128"
$SEC"1"
CDS_SEC"1"
MATERIAL"IC"
VALUE"PJT138K"
PART_TYPE"SMLF"
CDS_LIB"pure_quanta"
NEEDS_NO_SIZE"TRUE"
CDS_LMAN_SYM_OUTLINE"-150,150,150,-150"
PART_NUMBER"BAM138K0003";
"D1"
$PN"6"65;
"G1"
$PN"2"73;
"S1"
$PN"1"28;
%"UNIVERSAL_GND"
"1","(-975,3050)","0","pure_quanta_power","I38";
;
CDS_LIB"pure_quanta_power"
HDL_POWER"GND";
"A"28;
%"Q_RES"
"2","(-975,4025)","0","pure_quanta","I39";
;
LOCATION"R4125"
$SEC"1"
CDS_SEC"1"
VALUE"4.7K"
TOLERANCE"5%"
WATTAGE"1/16W"
MATERIAL"CHIP"
PACK_TYPE"0402LF"
CDS_LIB"pure_quanta"
PART_NUMBER"CS24702JB10";
"A"
$PN"1"29;
"B"
$PN"2"65;
%"Q_RES"
"2","(-2075,-725)","0","pure_quanta","I4";
;
LOCATION"R4153"
$SEC"1"
CDS_SEC"1"
MATERIAL"CHIP"
WATTAGE"1/16W"
TOLERANCE"1%"
VALUE"10K"
PACK_TYPE"0402LF"
CDS_LIB"pure_quanta"
PART_NUMBER"CS31002FB08";
"A"
$PN"1"34;
"B"
$PN"2"70;
%"MOSFET_NCH_DUAL"
"2","(150,2350)","0","pure_quanta","I40";
;
LOCATION"Q131"
$SEC"2"
CDS_SEC"2"
VALUE"PJT138K"
PART_TYPE"SMLF"
MATERIAL"IC"
CDS_LMAN_SYM_OUTLINE"-150,150,150,-150"
NEEDS_NO_SIZE"TRUE"
CDS_LIB"pure_quanta"
PART_NUMBER"BAM138K0003";
"S2"
$PN"4"42;
"G2"
$PN"5"69;
"D2"
$PN"3"61;
%"Q_RES"
"1","(-700,3025)","0","pure_quanta","I41";
;
LOCATION"R4572"
$SEC"1"
CDS_SEC"1"
TOLERANCE"5%"
VALUE"0"
WATTAGE"1/16W"
MATERIAL"EMPTY"
PACK_TYPE"0402LF"
CDS_LIB"pure_quanta"
PART_NUMBER"CS00002JB13";
"B"
$PN"2"61;
"A"
$PN"1"72;
%"MOSFET_NCH_DUAL"
"2","(125,3725)","0","pure_quanta","I42";
;
LOCATION"Q128"
$SEC"2"
CDS_SEC"2"
PART_TYPE"SMLF"
VALUE"PJT138K"
MATERIAL"IC"
CDS_LIB"pure_quanta"
NEEDS_NO_SIZE"TRUE"
CDS_LMAN_SYM_OUTLINE"-150,150,150,-150"
PART_NUMBER"BAM138K0003";
"S2"
$PN"4"30;
"G2"
$PN"5"65;
"D2"
$PN"3"74;
%"UNIVERSAL_POWER"
"1","(-975,4250)","0","pure_quanta_power","I43";
;
HDL_POWER"P3V3_AUX"
CDS_LIB"pure_quanta_power";
"A"29;
%"Q_RES"
"1","(-575,4475)","0","pure_quanta","I44";
;
LOCATION"R4575"
$SEC"1"
CDS_SEC"1"
PACK_TYPE"0402LF"
VALUE"0"
MATERIAL"EMPTY"
TOLERANCE"5%"
WATTAGE"1/16W"
CDS_LIB"pure_quanta"
PART_NUMBER"CS00002JB13";
"B"
$PN"2"74;
"A"
$PN"1"73;
%"UNIVERSAL_GND"
"1","(175,3350)","0","pure_quanta_power","I45";
;
CDS_LIB"pure_quanta_power"
HDL_POWER"GND";
"A"30;
%"UNIVERSAL_GND"
"1","(175,525)","0","pure_quanta_power","I46";
;
CDS_LIB"pure_quanta_power"
HDL_POWER"GND";
"A"31;
%"UNIVERSAL_GND"
"1","(250,-1025)","0","pure_quanta_power","I47";
;
CDS_LIB"pure_quanta_power"
HDL_POWER"GND";
"A"32;
%"Q_RES"
"2","(250,-225)","0","pure_quanta","I48";
;
LOCATION"R4156"
$SEC"1"
CDS_SEC"1"
VALUE"100K"
TOLERANCE"1%"
PACK_TYPE"0402LF"
WATTAGE"1/16W"
MATERIAL"CHIP"
CDS_LIB"pure_quanta"
PART_NUMBER"CS41002FB09";
"A"
$PN"1"40;
"B"
$PN"2"59;
%"UNIVERSAL_GND"
"1","(1025,-900)","0","pure_quanta_power","I49";
;
CDS_LIB"pure_quanta_power"
HDL_POWER"GND";
"A"33;
%"UNIVERSAL_POWER"
"1","(-2075,-475)","0","pure_quanta_power","I5";
;
HDL_POWER"P3V3_AUX"
CDS_LIB"pure_quanta_power";
"A"34;
%"Q_CAP"
"1","(1025,-700)","0","pure_quanta","I50";
;
LOCATION"C15"
$SEC"1"
CDS_SEC"1"
MATERIAL"X7R"
VALUE"0.1UF"
VOLTAGE"25V"
TOLERANCE"10%"
PACK_TYPE"0402"
CDS_LIB"pure_quanta"
PART_NUMBER"CH4104K1B00";
"B"
$PN"2"33;
"A"
$PN"1"59;
%"UNIVERSAL_GND"
"1","(2500,-1100)","0","pure_quanta_power","I53";
;
CDS_LIB"pure_quanta_power"
HDL_POWER"GND";
"A"35;
%"Q_RES"
"2","(2500,-825)","0","pure_quanta","I54";
;
LOCATION"R4559"
$SEC"1"
CDS_SEC"1"
TOLERANCE"1%"
PACK_TYPE"0402LF"
VALUE"100K"
WATTAGE"1/16W"
MATERIAL"CHIP"
CDS_LIB"pure_quanta"
PART_NUMBER"CS41002FB09";
"A"
$PN"1"58;
"B"
$PN"2"35;
%"Q_RES"
"2","(2475,-350)","0","pure_quanta","I55";
;
LOCATION"R4562"
$SEC"1"
CDS_SEC"1"
PACK_TYPE"0402LF"
VALUE"100K"
WATTAGE"1/16W"
TOLERANCE"1%"
MATERIAL"EMPTY"
CDS_LIB"pure_quanta"
PART_NUMBER"CS41002FB09";
"A"
$PN"1"36;
"B"
$PN"2"58;
%"UNIVERSAL_POWER"
"1","(2475,-100)","0","pure_quanta_power","I56";
;
HDL_POWER"P3V3_AUX"
CDS_LIB"pure_quanta_power";
"A"36;
%"MOSFET_NCH_DUAL"
"1","(3600,-575)","0","pure_quanta","I57";
;
LOCATION"Q146"
$SEC"1"
CDS_SEC"1"
VALUE"PJT138K"
MATERIAL"IC"
PART_TYPE"SMLF"
CDS_LMAN_SYM_OUTLINE"-150,150,150,-150"
NEEDS_NO_SIZE"TRUE"
CDS_LIB"pure_quanta"
PART_NUMBER"BAM138K0003";
"D1"
$PN"6"63;
"G1"
$PN"2"58;
"S1"
$PN"1"37;
%"UNIVERSAL_GND"
"1","(3650,-950)","0","pure_quanta_power","I58";
;
CDS_LIB"pure_quanta_power"
HDL_POWER"GND";
"A"37;
%"UNIVERSAL_GND"
"1","(4800,-650)","0","pure_quanta_power","I59";
;
CDS_LIB"pure_quanta_power"
HDL_POWER"GND";
"A"38;
%"MOSFET_NCH_DUAL"
"1","(-950,-950)","0","pure_quanta","I6";
;
LOCATION"Q134"
$SEC"1"
CDS_SEC"1"
VALUE"PJT138K"
PART_TYPE"SMLF"
MATERIAL"IC"
CDS_LIB"pure_quanta"
NEEDS_NO_SIZE"TRUE"
CDS_LMAN_SYM_OUTLINE"-150,150,150,-150"
PART_NUMBER"BAM138K0003";
"D1"
$PN"6"62;
"G1"
$PN"2"70;
"S1"
$PN"1"43;
%"UNIVERSAL_GND"
"1","(5575,-525)","0","pure_quanta_power","I60";
;
CDS_LIB"pure_quanta_power"
HDL_POWER"GND";
"A"39;
%"Q_CAP"
"1","(5575,-325)","0","pure_quanta","I61";
;
LOCATION"C18"
$SEC"1"
CDS_SEC"1"
VALUE"0.1UF"
VOLTAGE"25V"
TOLERANCE"10%"
MATERIAL"X7R"
PACK_TYPE"0402"
CDS_LIB"pure_quanta"
PART_NUMBER"CH4104K1B00";
"B"
$PN"2"39;
"A"
$PN"1"57;
%"Q_RES"
"2","(3650,25)","0","pure_quanta","I62";
;
LOCATION"R4560"
$SEC"1"
CDS_SEC"1"
WATTAGE"1/16W"
PACK_TYPE"0402LF"
TOLERANCE"5%"
MATERIAL"CHIP"
VALUE"4.7K"
CDS_LIB"pure_quanta"
PART_NUMBER"CS24702JB10";
"A"
$PN"1"50;
"B"
$PN"2"63;
%"UNIVERSAL_POWER"
"1","(250,0)","0","pure_quanta_power","I63";
;
HDL_POWER"P3V3_AUX"
CDS_LIB"pure_quanta_power";
"A"40;
%"Q_CAP"
"1","(950,850)","0","pure_quanta","I64";
;
LOCATION"C13"
$SEC"1"
CDS_SEC"1"
TOLERANCE"10%"
MATERIAL"X7R"
PACK_TYPE"0402"
VOLTAGE"25V"
VALUE"0.1UF"
CDS_LIB"pure_quanta"
PART_NUMBER"CH4104K1B00";
"B"
$PN"2"41;
"A"
$PN"1"60;
%"UNIVERSAL_GND"
"1","(950,650)","0","pure_quanta_power","I65";
;
CDS_LIB"pure_quanta_power"
HDL_POWER"GND";
"A"41;
%"Q_RES"
"2","(175,1325)","0","pure_quanta","I66";
;
LOCATION"R4129"
$SEC"1"
CDS_SEC"1"
TOLERANCE"1%"
VALUE"100K"
MATERIAL"CHIP"
WATTAGE"1/16W"
PACK_TYPE"0402LF"
CDS_LIB"pure_quanta"
PART_NUMBER"CS41002FB09";
"A"
$PN"1"26;
"B"
$PN"2"60;
%"UNIVERSAL_GND"
"1","(200,1975)","0","pure_quanta_power","I67";
;
CDS_LIB"pure_quanta_power"
HDL_POWER"GND";
"A"42;
%"UNIVERSAL_GND"
"1","(-900,-1325)","0","pure_quanta_power","I7";
;
CDS_LIB"pure_quanta_power"
HDL_POWER"GND";
"A"43;
%"Q_RES"
"2","(200,2775)","0","pure_quanta","I70";
;
LOCATION"R4130"
$SEC"1"
CDS_SEC"1"
MATERIAL"CHIP"
PACK_TYPE"0402LF"
WATTAGE"1/16W"
VALUE"100K"
TOLERANCE"1%"
CDS_LIB"pure_quanta"
PART_NUMBER"CS41002FB09";
"A"
$PN"1"44;
"B"
$PN"2"61;
%"UNIVERSAL_POWER"
"1","(200,3000)","0","pure_quanta_power","I71";
;
HDL_POWER"P3V3_AUX"
CDS_LIB"pure_quanta_power";
"A"44;
%"UNIVERSAL_GND"
"1","(975,2100)","0","pure_quanta_power","I72";
;
CDS_LIB"pure_quanta_power"
HDL_POWER"GND";
"A"45;
%"Q_CAP"
"1","(975,2300)","0","pure_quanta","I73";
;
LOCATION"C14"
$SEC"1"
CDS_SEC"1"
MATERIAL"X7R"
TOLERANCE"10%"
VOLTAGE"25V"
PACK_TYPE"0402"
VALUE"0.1UF"
CDS_LIB"pure_quanta"
PART_NUMBER"CH4104K1B00";
"B"
$PN"2"45;
"A"
$PN"1"61;
%"UNIVERSAL_GND"
"1","(950,3475)","0","pure_quanta_power","I74";
;
CDS_LIB"pure_quanta_power"
HDL_POWER"GND";
"A"46;
%"Q_CAP"
"1","(950,3675)","0","pure_quanta","I75";
;
LOCATION"C12"
$SEC"1"
CDS_SEC"1"
VALUE"0.1UF"
TOLERANCE"10%"
MATERIAL"X7R"
VOLTAGE"25V"
PACK_TYPE"0402"
CDS_LIB"pure_quanta"
PART_NUMBER"CH4104K1B00";
"B"
$PN"2"46;
"A"
$PN"1"74;
%"Q_RES"
"2","(-900,-350)","0","pure_quanta","I8";
;
LOCATION"R4155"
$SEC"1"
CDS_SEC"1"
MATERIAL"CHIP"
PACK_TYPE"0402LF"
WATTAGE"1/16W"
TOLERANCE"5%"
VALUE"4.7K"
CDS_LIB"pure_quanta"
PART_NUMBER"CS24702JB10";
"A"
$PN"1"53;
"B"
$PN"2"62;
%"UNIVERSAL_GND"
"1","(2500,375)","0","pure_quanta_power","I80";
;
CDS_LIB"pure_quanta_power"
HDL_POWER"GND";
"A"47;
%"Q_RES"
"2","(2500,650)","0","pure_quanta","I81";
;
LOCATION"R4134"
$SEC"1"
CDS_SEC"1"
PACK_TYPE"0402LF"
TOLERANCE"1%"
MATERIAL"EMPTY"
WATTAGE"1/16W"
VALUE"100K"
CDS_LIB"pure_quanta"
PART_NUMBER"CS41002FB09";
"A"
$PN"1"75;
"B"
$PN"2"47;
%"Q_RES"
"2","(2475,1125)","0","pure_quanta","I82";
;
LOCATION"R4133"
$SEC"1"
CDS_SEC"1"
VALUE"54.9K"
TOLERANCE"1%"
WATTAGE"1/16W"
PACK_TYPE"0402LF"
MATERIAL"EMPTY"
CDS_LIB"pure_quanta"
PART_NUMBER"CS35492FB03";
"A"
$PN"1"48;
"B"
$PN"2"75;
%"UNIVERSAL_POWER"
"1","(2475,1375)","0","pure_quanta_power","I83";
;
HDL_POWER"P3V3_AUX"
CDS_LIB"pure_quanta_power";
"A"48;
%"UNIVERSAL_GND"
"1","(2525,1825)","0","pure_quanta_power","I84";
;
CDS_LIB"pure_quanta_power"
HDL_POWER"GND";
"A"49;
%"UNIVERSAL_POWER"
"1","(3650,250)","0","pure_quanta_power","I85";
;
HDL_POWER"P3V3_AUX"
CDS_LIB"pure_quanta_power";
"A"50;
%"MOSFET_NCH_DUAL"
"1","(3600,900)","0","pure_quanta","I86";
;
LOCATION"Q129"
$SEC"1"
CDS_SEC"1"
PART_TYPE"SMLF"
VALUE"PJT138K"
MATERIAL"IC"
CDS_LMAN_SYM_OUTLINE"-150,150,150,-150"
NEEDS_NO_SIZE"TRUE"
CDS_LIB"pure_quanta"
PART_NUMBER"BAM138K0003";
"D1"
$PN"6"66;
"G1"
$PN"2"75;
"S1"
$PN"1"51;
%"UNIVERSAL_GND"
"1","(3650,525)","0","pure_quanta_power","I87";
;
CDS_LIB"pure_quanta_power"
HDL_POWER"GND";
"A"51;
%"Q_RES"
"2","(3650,1500)","0","pure_quanta","I88";
;
LOCATION"R4138"
$SEC"1"
CDS_SEC"1"
MATERIAL"CHIP"
WATTAGE"1/16W"
PACK_TYPE"0402LF"
TOLERANCE"5%"
VALUE"4.7K"
CDS_LIB"pure_quanta"
PART_NUMBER"CS24702JB10";
"A"
$PN"1"52;
"B"
$PN"2"66;
%"UNIVERSAL_POWER"
"1","(3650,1725)","0","pure_quanta_power","I89";
;
HDL_POWER"P3V3_AUX"
CDS_LIB"pure_quanta_power";
"A"52;
%"UNIVERSAL_POWER"
"1","(-900,-125)","0","pure_quanta_power","I9";
;
HDL_POWER"P3V3_AUX"
CDS_LIB"pure_quanta_power";
"A"53;
%"UNIVERSAL_GND"
"1","(3675,1975)","0","pure_quanta_power","I90";
;
CDS_LIB"pure_quanta_power"
HDL_POWER"GND";
"A"54;
%"Q_RES"
"1","(3925,1875)","0","pure_quanta","I91";
;
LOCATION"R4576"
$SEC"1"
CDS_SEC"1"
PACK_TYPE"0402LF"
TOLERANCE"5%"
MATERIAL"EMPTY"
VALUE"0"
WATTAGE"1/16W"
CDS_LIB"pure_quanta"
PART_NUMBER"CS00002JB13";
"B"
$PN"2"78;
"A"
$PN"1"75;
%"Q_RES"
"2","(2525,2100)","0","pure_quanta","I92";
;
LOCATION"R4136"
$SEC"1"
CDS_SEC"1"
WATTAGE"1/16W"
TOLERANCE"1%"
PACK_TYPE"0402LF"
MATERIAL"EMPTY"
VALUE"100K"
CDS_LIB"pure_quanta"
PART_NUMBER"CS41002FB09";
"A"
$PN"1"76;
"B"
$PN"2"49;
%"Q_RES"
"2","(2500,2575)","0","pure_quanta","I93";
;
LOCATION"R4135"
$SEC"1"
CDS_SEC"1"
PACK_TYPE"0402LF"
WATTAGE"1/16W"
MATERIAL"CHIP"
TOLERANCE"1%"
VALUE"10K"
CDS_LIB"pure_quanta"
PART_NUMBER"CS31002FB08";
"A"
$PN"1"55;
"B"
$PN"2"76;
%"UNIVERSAL_POWER"
"1","(2500,2825)","0","pure_quanta_power","I94";
;
HDL_POWER"P3V3_AUX"
CDS_LIB"pure_quanta_power";
"A"55;
%"UNIVERSAL_GND"
"1","(2500,3200)","0","pure_quanta_power","I95";
;
CDS_LIB"pure_quanta_power"
HDL_POWER"GND";
"A"56;
%"Q_RES"
"2","(2500,3475)","0","pure_quanta","I96";
;
LOCATION"R4132"
$SEC"1"
CDS_SEC"1"
WATTAGE"1/16W"
TOLERANCE"1%"
VALUE"100K"
MATERIAL"EMPTY"
PACK_TYPE"0402LF"
CDS_LIB"pure_quanta"
PART_NUMBER"CS41002FB09";
"A"
$PN"1"77;
"B"
$PN"2"56;
%"Q_RES"
"2","(2475,3950)","0","pure_quanta","I97";
;
LOCATION"R4131"
$SEC"1"
CDS_SEC"1"
TOLERANCE"1%"
VALUE"54.9K"
PACK_TYPE"0402LF"
MATERIAL"EMPTY"
WATTAGE"1/16W"
CDS_LIB"pure_quanta"
PART_NUMBER"CS35492FB03";
"A"
$PN"1"5;
"B"
$PN"2"77;
%"MOSFET_NCH_DUAL"
"1","(3625,2350)","0","pure_quanta","I98";
;
LOCATION"Q133"
$SEC"1"
CDS_SEC"1"
MATERIAL"IC"
PART_TYPE"SMLF"
VALUE"PJT138K"
CDS_LMAN_SYM_OUTLINE"-150,150,150,-150"
NEEDS_NO_SIZE"TRUE"
CDS_LIB"pure_quanta"
PART_NUMBER"BAM138K0003";
"D1"
$PN"6"67;
"G1"
$PN"2"76;
"S1"
$PN"1"54;
%"Q_RES"
"2","(3675,2950)","0","pure_quanta","I99";
;
LOCATION"R4139"
$SEC"1"
CDS_SEC"1"
TOLERANCE"5%"
VALUE"4.7K"
WATTAGE"1/16W"
MATERIAL"CHIP"
PACK_TYPE"0402LF"
CDS_LIB"pure_quanta"
PART_NUMBER"CS24702JB10";
"A"
$PN"1"2;
"B"
$PN"2"67;
END.
